# S9S_MB_2U (Grand Teton) — schematic netlist excerpt (pin names and nets, part order shuffled) for the footprints in the layout excerpt that follows; sources: Cadence DE-HDL packaged netlist, KiCad conversion of 03242023_DA0F0TMBIJ0_F0T_Motherboard_J_brd_V01_OCP.brd

R4759  Q_RES  49.9 1% CHIP  pkg 0402LF  page 164 : A = OCP_V3_2_AUX_PWR_EN_R2 ; B = OCP_V3_2_AUX_PWR_EN
R3845  Q_RES  0 5% EMPTY  pkg 0402LF  page 157 : A = HP_LVC3_OCP_V3_1_EN ; B = P3V3_OCP_EN_1_R2

(kicad_pcb
	(version 20260206)
	(generator "pcbnew")
	(generator_version "10.0")
	(general
		(thickness 1.6)
		(legacy_teardrops no)
	)
	(paper "A4")
	(title_block
		(title "03242023_DA0F0TMBIJ0_F0T_Motherboard_J_brd_V01_OCP.brd")
		(comment 1 "Grand Teton / footprints 566-567 of 6105")
	)
	(layers
		(0 "F.Cu" signal "TOP")
		(4 "In1.Cu" signal "GND")
		(6 "In2.Cu" signal "IN1")
		(8 "In3.Cu" signal "GND1")
		(10 "In4.Cu" signal "IN2")
		(12 "In5.Cu" signal "GND2")
		(14 "In6.Cu" signal "IN3")
		(16 "In7.Cu" signal "GND3")
		(18 "In8.Cu" signal "VCC")
		(20 "In9.Cu" signal "VCC1")
		(22 "In10.Cu" signal "GND4")
		(24 "In11.Cu" signal "IN4")
		(26 "In12.Cu" signal "GND5")
		(28 "In13.Cu" signal "IN5")
		(30 "In14.Cu" signal "GND6")
		(32 "In15.Cu" signal "IN6")
		(34 "In16.Cu" signal "GND7")
		(2 "B.Cu" signal "BOTTOM")
		(9 "F.Adhes" user "F.Adhesive")
		(11 "B.Adhes" user "B.Adhesive")
		(13 "F.Paste" user "Package Geometry/Pastemask Top")
		(15 "B.Paste" user "Package Geometry/Pastemask Bottom")
		(5 "F.SilkS" user "Ref Des/Silkscreen Top")
		(7 "B.SilkS" user "Ref Des/Silkscreen Bottom")
		(1 "F.Mask" user "Board Geometry/Soldermask Top")
		(3 "B.Mask" user "Board Geometry/Soldermask Bottom")
		(17 "Dwgs.User" user "User.Drawings")
		(19 "Cmts.User" user "User.Comments")
		(21 "Eco1.User" user "User.Eco1")
		(23 "Eco2.User" user "User.Eco2")
		(25 "Edge.Cuts" user "Board Geometry/Outline")
		(27 "Margin" user)
		(31 "F.CrtYd" user "Package Geometry/Place Bound Top")
		(29 "B.CrtYd" user "Package Geometry/Place Bound Bottom")
		(35 "F.Fab" user "Ref Des/Assembly Top")
		(33 "B.Fab" user "Ref Des/Assembly Bottom")
	)
	(footprint ""
		(layer "F.Cu")
		(at 143.90116 -112.434624)
		(property "Reference" "R4759"
			(at 0 0 0)
			(layer "F.SilkS")
			(hide yes)
			(effects
				(font
					(size 1.27 1.27)
				)
			)
		)
		(property "Value" ""
			(at 0 0 0)
			(layer "F.Fab")
			(effects
				(font
					(size 1.27 1.27)
				)
			)
		)
		(duplicate_pad_numbers_are_jumpers no)
		(fp_line
			(start -0.7874 -0.4064)
			(end 0.7874 -0.4064)
			(stroke
				(width 0.1524)
				(type default)
			)
			(layer "F.SilkS")
		)
		(fp_line
			(start -0.7874 0.4064)
			(end -0.7874 -0.4064)
			(stroke
				(width 0.1524)
				(type default)
			)
			(layer "F.SilkS")
		)
		(fp_line
			(start 0.7874 -0.4064)
			(end 0.7874 0.4064)
			(stroke
				(width 0.1524)
				(type default)
			)
			(layer "F.SilkS")
		)
		(fp_line
			(start 0.7874 0.4064)
			(end -0.7874 0.4064)
			(stroke
				(width 0.1524)
				(type default)
			)
			(layer "F.SilkS")
		)
		(fp_line
			(start -0.67945 -0.305054)
			(end -0.12065 -0.305054)
			(stroke
				(width 0.1)
				(type default)
			)
			(layer "F.Fab")
		)
		(fp_line
			(start -0.67945 0.3048)
			(end -0.67945 -0.305054)
			(stroke
				(width 0.1)
				(type default)
			)
			(layer "F.Fab")
		)
		(fp_line
			(start -0.12065 -0.305054)
			(end -0.12065 -0.2794)
			(stroke
				(width 0.1)
				(type default)
			)
			(layer "F.Fab")
		)
		(fp_line
			(start -0.12065 -0.2794)
			(end 0.12065 -0.2794)
			(stroke
				(width 0.1)
				(type default)
			)
			(layer "F.Fab")
		)
		(fp_line
			(start -0.12065 0.2794)
			(end -0.12065 0.3048)
			(stroke
				(width 0.1)
				(type default)
			)
			(layer "F.Fab")
		)
		(fp_line
			(start -0.12065 0.3048)
			(end -0.67945 0.3048)
			(stroke
				(width 0.1)
				(type default)
			)
			(layer "F.Fab")
		)
		(fp_line
			(start 0.120396 0.2794)
			(end -0.12065 0.2794)
			(stroke
				(width 0.1)
				(type default)
			)
			(layer "F.Fab")
		)
		(fp_line
			(start 0.120396 0.3048)
			(end 0.120396 0.2794)
			(stroke
				(width 0.1)
				(type default)
			)
			(layer "F.Fab")
		)
		(fp_line
			(start 0.12065 -0.3048)
			(end 0.67945 -0.3048)
			(stroke
				(width 0.1)
				(type default)
			)
			(layer "F.Fab")
		)
		(fp_line
			(start 0.12065 -0.2794)
			(end 0.12065 -0.3048)
			(stroke
				(width 0.1)
				(type default)
			)
			(layer "F.Fab")
		)
		(fp_line
			(start 0.67945 -0.3048)
			(end 0.67945 0.3048)
			(stroke
				(width 0.1)
				(type default)
			)
			(layer "F.Fab")
		)
		(fp_line
			(start 0.67945 0.3048)
			(end 0.120396 0.3048)
			(stroke
				(width 0.1)
				(type default)
			)
			(layer "F.Fab")
		)
		(pad "1" smd circle
			(at -0.40005 0)
			(size 0 0)
			(layers "F.Cu" "F.Mask" "F.Paste")
			(net "OCP_V3_2_AUX_PWR_EN_R2")
		)
		(pad "2" smd circle
			(at 0.40005 0)
			(size 0 0)
			(layers "F.Cu" "F.Mask" "F.Paste")
			(net "OCP_V3_2_AUX_PWR_EN")
		)
	)
	(footprint ""
		(layer "F.Cu")
		(at 420.14394 -109.271308 -90)
		(property "Reference" "R3845"
			(at 0 0 270)
			(layer "F.SilkS")
			(hide yes)
			(effects
				(font
					(size 1.27 1.27)
				)
			)
		)
		(property "Value" ""
			(at 0 0 270)
			(layer "F.Fab")
			(effects
				(font
					(size 1.27 1.27)
				)
			)
		)
		(duplicate_pad_numbers_are_jumpers no)
		(fp_line
			(start -0.7874 0.4064)
			(end -0.7874 -0.4064)
			(stroke
				(width 0.1524)
				(type default)
			)
			(layer "F.SilkS")
		)
		(fp_line
			(start 0.7874 0.4064)
			(end -0.7874 0.4064)
			(stroke
				(width 0.1524)
				(type default)
			)
			(layer "F.SilkS")
		)
		(fp_line
			(start -0.7874 -0.4064)
			(end 0.7874 -0.4064)
			(stroke
				(width 0.1524)
				(type default)
			)
			(layer "F.SilkS")
		)
		(fp_line
			(start 0.7874 -0.4064)
			(end 0.7874 0.4064)
			(stroke
				(width 0.1524)
				(type default)
			)
			(layer "F.SilkS")
		)
		(fp_line
			(start -0.67945 0.3048)
			(end -0.67945 -0.305054)
			(stroke
				(width 0.1)
				(type default)
			)
			(layer "F.Fab")
		)
		(fp_line
			(start -0.12065 0.3048)
			(end -0.67945 0.3048)
			(stroke
				(width 0.1)
				(type default)
			)
			(layer "F.Fab")
		)
		(fp_line
			(start 0.120396 0.3048)
			(end 0.120396 0.2794)
			(stroke
				(width 0.1)
				(type default)
			)
			(layer "F.Fab")
		)
		(fp_line
			(start 0.67945 0.3048)
			(end 0.120396 0.3048)
			(stroke
				(width 0.1)
				(type default)
			)
			(layer "F.Fab")
		)
		(fp_line
			(start -0.12065 0.2794)
			(end -0.12065 0.3048)
			(stroke
				(width 0.1)
				(type default)
			)
			(layer "F.Fab")
		)
		(fp_line
			(start 0.120396 0.2794)
			(end -0.12065 0.2794)
			(stroke
				(width 0.1)
				(type default)
			)
			(layer "F.Fab")
		)
		(fp_line
			(start -0.12065 -0.2794)
			(end 0.12065 -0.2794)
			(stroke
				(width 0.1)
				(type default)
			)
			(layer "F.Fab")
		)
		(fp_line
			(start 0.12065 -0.2794)
			(end 0.12065 -0.3048)
			(stroke
				(width 0.1)
				(type default)
			)
			(layer "F.Fab")
		)
		(fp_line
			(start 0.12065 -0.3048)
			(end 0.67945 -0.3048)
			(stroke
				(width 0.1)
				(type default)
			)
			(layer "F.Fab")
		)
		(fp_line
			(start 0.67945 -0.3048)
			(end 0.67945 0.3048)
			(stroke
				(width 0.1)
				(type default)
			)
			(layer "F.Fab")
		)
		(fp_line
			(start -0.67945 -0.305054)
			(end -0.12065 -0.305054)
			(stroke
				(width 0.1)
				(type default)
			)
			(layer "F.Fab")
		)
		(fp_line
			(start -0.12065 -0.305054)
			(end -0.12065 -0.2794)
			(stroke
				(width 0.1)
				(type default)
			)
			(layer "F.Fab")
		)
		(pad "1" smd circle
			(at -0.40005 0 270)
			(size 0 0)
			(layers "F.Cu" "F.Mask" "F.Paste")
			(net "HP_LVC3_OCP_V3_1_EN")
		)
		(pad "2" smd circle
			(at 0.40005 0 270)
			(size 0 0)
			(layers "F.Cu" "F.Mask" "F.Paste")
			(net "P3V3_OCP_EN_1_R2")
		)
	)
)
